# TIMECARD (Time Appliance Project (Time Card)) — schematic netlist excerpt (pin names and nets, part order shuffled) for the footprints in the layout excerpt that follows; sources: Cadence DE-HDL packaged netlist, KiCad conversion of R4006-B0001-02_R01.brd

MAC_PIN4  NUT  pkg P_NUT_079C100  page 21 : \1\ = SG
MAC_PIN5  NUT  pkg P_NUT_079C100  page 21 : \1\ = XP5R0V_MAC
SP55  NULL  pkg DUMMY  page 34
SP28  SOLDER_PREFORM  pkg 0201_SOLDER_PREFORM_4MIL  page 34 : \1\ = NC ; \2\ = NC

(kicad_pcb
	(version 20260206)
	(generator "pcbnew")
	(generator_version "10.0")
	(general
		(thickness 1.6)
		(legacy_teardrops no)
	)
	(paper "A4")
	(title_block
		(title "timecard-production-celestica-r4006 — R4006-B0001-02_R01.brd")
		(comment 1 "Time Appliance Project (Time Card) / footprints 539-542 of 1113")
	)
	(layers
		(0 "F.Cu" signal "TOP")
		(4 "In1.Cu" signal "L02_GND1")
		(6 "In2.Cu" signal "L03_SIG1")
		(8 "In3.Cu" signal "L04_GND2")
		(10 "In4.Cu" signal "L05_VCC1")
		(12 "In5.Cu" signal "L06_VCC2")
		(14 "In6.Cu" signal "L07_GND3")
		(16 "In7.Cu" signal "L08_SIG2")
		(18 "In8.Cu" signal "L09_GND4")
		(2 "B.Cu" signal "BOTTOM")
		(9 "F.Adhes" user "F.Adhesive")
		(11 "B.Adhes" user "B.Adhesive")
		(13 "F.Paste" user "Package Geometry/Pastemask Top")
		(15 "B.Paste" user "Package Geometry/Pastemask Bottom")
		(5 "F.SilkS" user "Ref Des/Silkscreen Top")
		(7 "B.SilkS" user "Ref Des/Silkscreen Bottom")
		(1 "F.Mask" user "Board Geometry/Soldermask Top")
		(3 "B.Mask" user "Board Geometry/Soldermask Bottom")
		(17 "Dwgs.User" user "User.Drawings")
		(19 "Cmts.User" user "User.Comments")
		(21 "Eco1.User" user "User.Eco1")
		(23 "Eco2.User" user "User.Eco2")
		(25 "Edge.Cuts" user "Board Geometry/Outline")
		(27 "Margin" user)
		(31 "F.CrtYd" user "Package Geometry/Place Bound Top")
		(29 "B.CrtYd" user "Package Geometry/Place Bound Bottom")
		(35 "F.Fab" user "Ref Des/Assembly Top")
		(33 "B.Fab" user "Ref Des/Assembly Bottom")
	)
	(footprint ""
		(layer "F.Cu")
		(at 72.661018 -67.066922)
		(property "Reference" "MAC_PIN5"
			(at 0.998982 -3.129026 0)
			(unlocked yes)
			(layer "F.SilkS")
			(effects
				(font
					(size 0.7874 0.5842)
					(thickness 0.1524)
				)
			)
		)
		(property "Value" ""
			(at 0 0 0)
			(layer "F.Fab")
			(effects
				(font
					(size 1.27 1.27)
				)
			)
		)
		(property "Device Type" "NUT-A200-00029-FB"
			(at 0 2.632964 0)
			(unlocked yes)
			(layer "F.Fab")
			(hide yes)
			(effects
				(font
					(size 0.7874 0.5842)
					(thickness 0.1524)
				)
			)
		)
		(property "User Part Number" "PARTNUM*"
			(at 0 3.826764 0)
			(unlocked yes)
			(layer "Cmts.User")
			(hide yes)
			(effects
				(font
					(size 0.7874 0.5842)
					(thickness 0.1524)
				)
			)
		)
		(duplicate_pad_numbers_are_jumpers no)
		(fp_circle
			(center 0 0)
			(end 1.524 0)
			(stroke
				(width 0.1)
				(type default)
			)
			(fill no)
			(layer "F.SilkS")
		)
		(fp_poly
			(pts
				(arc
					(start -1.260856 -0.1524)
					(mid -0.898049 -0.898049)
					(end -0.1524 -1.260856)
				)
				(arc
					(start -0.1524 -0.991616)
					(mid -0.709411 -0.709411)
					(end -0.991616 -0.1524)
				)
			)
			(stroke
				(width 0)
				(type default)
			)
			(fill yes)
			(layer "F.Paste")
		)
		(fp_poly
			(pts
				(arc
					(start -0.1524 1.260856)
					(mid -0.898049 0.898049)
					(end -1.260856 0.1524)
				)
				(arc
					(start -0.991616 0.1524)
					(mid -0.709411 0.709411)
					(end -0.1524 0.991616)
				)
			)
			(stroke
				(width 0)
				(type default)
			)
			(fill yes)
			(layer "F.Paste")
		)
		(fp_poly
			(pts
				(arc
					(start 0.1524 -1.260856)
					(mid 0.898049 -0.898049)
					(end 1.260856 -0.1524)
				)
				(arc
					(start 0.991616 -0.1524)
					(mid 0.709411 -0.709411)
					(end 0.1524 -0.991616)
				)
			)
			(stroke
				(width 0)
				(type default)
			)
			(fill yes)
			(layer "F.Paste")
		)
		(fp_poly
			(pts
				(arc
					(start 1.260856 0.1524)
					(mid 0.898049 0.898049)
					(end 0.1524 1.260856)
				)
				(arc
					(start 0.1524 0.991616)
					(mid 0.709411 0.709411)
					(end 0.991616 0.1524)
				)
			)
			(stroke
				(width 0)
				(type default)
			)
			(fill yes)
			(layer "F.Paste")
		)
		(fp_poly
			(pts
				(arc
					(start 6.35 0)
					(mid -6.35 0)
					(end 6.35 0)
				)
			)
			(stroke
				(width 0)
				(type default)
			)
			(fill no)
			(layer "B.CrtYd")
		)
		(fp_poly
			(pts
				(arc
					(start 1.778 0)
					(mid -1.778 0)
					(end 1.778 0)
				)
			)
			(stroke
				(width 0)
				(type default)
			)
			(fill no)
			(layer "F.CrtYd")
		)
		(fp_circle
			(center 0 0)
			(end 1.1684 0)
			(stroke
				(width 0.1)
				(type default)
			)
			(fill no)
			(layer "F.Fab")
		)
		(pad "1" thru_hole circle
			(at 0 0)
			(size 2.54 2.54)
			(drill 2.0066)
			(layers "*.Cu" "*.Mask")
			(remove_unused_layers no)
			(net "XP5R0V_MAC")
			(thermal_gap 0.0254)
			(padstack
				(mode front_inner_back)
				(layer "Inner"
					(shape circle)
					(size 2.54 2.54)
					(clearance 0.0254)
				)
				(layer "B.Cu"
					(shape circle)
					(size 2.54 2.54)
				)
			)
		)
	)
	(footprint ""
		(layer "F.Cu")
		(at 52.07 -125.73)
		(property "Reference" "SP55"
			(at 0 0 0)
			(layer "F.SilkS")
			(hide yes)
			(effects
				(font
					(size 1.27 1.27)
				)
			)
		)
		(property "Value" ""
			(at 0 0 0)
			(layer "F.Fab")
			(effects
				(font
					(size 1.27 1.27)
				)
			)
		)
		(duplicate_pad_numbers_are_jumpers no)
	)
	(footprint ""
		(layer "F.Cu")
		(at 57.785 -130.556)
		(property "Reference" "SP28"
			(at 0 0 0)
			(layer "F.SilkS")
			(hide yes)
			(effects
				(font
					(size 1.27 1.27)
				)
			)
		)
		(property "Value" ""
			(at 0 0 0)
			(layer "F.Fab")
			(effects
				(font
					(size 1.27 1.27)
				)
			)
		)
		(duplicate_pad_numbers_are_jumpers no)
	)
	(footprint ""
		(layer "F.Cu")
		(at 72.661018 -26.426922)
		(property "Reference" "MAC_PIN4"
			(at 2.921762 2.580132 0)
			(unlocked yes)
			(layer "F.SilkS")
			(effects
				(font
					(size 0.7874 0.5842)
					(thickness 0.1524)
				)
			)
		)
		(property "Value" ""
			(at 0 0 0)
			(layer "F.Fab")
			(effects
				(font
					(size 1.27 1.27)
				)
			)
		)
		(property "User Part Number" "PARTNUM*"
			(at 0 3.826764 0)
			(unlocked yes)
			(layer "Cmts.User")
			(hide yes)
			(effects
				(font
					(size 0.7874 0.5842)
					(thickness 0.1524)
				)
			)
		)
		(property "Device Type" "NUT-A200-00029-FB"
			(at 0 2.632964 0)
			(unlocked yes)
			(layer "F.Fab")
			(hide yes)
			(effects
				(font
					(size 0.7874 0.5842)
					(thickness 0.1524)
				)
			)
		)
		(duplicate_pad_numbers_are_jumpers no)
		(fp_circle
			(center 0 0)
			(end 1.524 0)
			(stroke
				(width 0.1)
				(type default)
			)
			(fill no)
			(layer "F.SilkS")
		)
		(fp_poly
			(pts
				(arc
					(start -1.260856 -0.1524)
					(mid -0.898049 -0.898049)
					(end -0.1524 -1.260856)
				)
				(arc
					(start -0.1524 -0.991616)
					(mid -0.709411 -0.709411)
					(end -0.991616 -0.1524)
				)
			)
			(stroke
				(width 0)
				(type default)
			)
			(fill yes)
			(layer "F.Paste")
		)
		(fp_poly
			(pts
				(arc
					(start -0.1524 1.260856)
					(mid -0.898049 0.898049)
					(end -1.260856 0.1524)
				)
				(arc
					(start -0.991616 0.1524)
					(mid -0.709411 0.709411)
					(end -0.1524 0.991616)
				)
			)
			(stroke
				(width 0)
				(type default)
			)
			(fill yes)
			(layer "F.Paste")
		)
		(fp_poly
			(pts
				(arc
					(start 0.1524 -1.260856)
					(mid 0.898049 -0.898049)
					(end 1.260856 -0.1524)
				)
				(arc
					(start 0.991616 -0.1524)
					(mid 0.709411 -0.709411)
					(end 0.1524 -0.991616)
				)
			)
			(stroke
				(width 0)
				(type default)
			)
			(fill yes)
			(layer "F.Paste")
		)
		(fp_poly
			(pts
				(arc
					(start 1.260856 0.1524)
					(mid 0.898049 0.898049)
					(end 0.1524 1.260856)
				)
				(arc
					(start 0.1524 0.991616)
					(mid 0.709411 0.709411)
					(end 0.991616 0.1524)
				)
			)
			(stroke
				(width 0)
				(type default)
			)
			(fill yes)
			(layer "F.Paste")
		)
		(fp_poly
			(pts
				(arc
					(start 6.35 0)
					(mid -6.35 0)
					(end 6.35 0)
				)
			)
			(stroke
				(width 0)
				(type default)
			)
			(fill no)
			(layer "B.CrtYd")
		)
		(fp_poly
			(pts
				(arc
					(start 1.778 0)
					(mid -1.778 0)
					(end 1.778 0)
				)
			)
			(stroke
				(width 0)
				(type default)
			)
			(fill no)
			(layer "F.CrtYd")
		)
		(fp_circle
			(center 0 0)
			(end 1.1684 0)
			(stroke
				(width 0.1)
				(type default)
			)
			(fill no)
			(layer "F.Fab")
		)
		(pad "1" thru_hole circle
			(at 0 0)
			(size 2.54 2.54)
			(drill 2.0066)
			(layers "*.Cu" "*.Mask")
			(remove_unused_layers no)
			(net "SG")
			(thermal_gap 0.0254)
			(padstack
				(mode front_inner_back)
				(layer "Inner"
					(shape circle)
					(size 2.54 2.54)
					(clearance 0.0254)
				)
				(layer "B.Cu"
					(shape circle)
					(size 2.54 2.54)
				)
			)
		)
	)
)
